(kicad_sch (version 20211123) (generator eeschema)

  (paper "A3")

  (title_block
    (title "SA800U (Snapdragon 845) Baseboard")
    (date "2023-10-19")
    (rev "1.0.3")
    (company "Antmicro Ltd.")
    (comment 1 "www.antmicro.com")
  )

  (junction (at 148.971 121.031) (diameter 0) (color 0 0 0 0)
  )
  (junction (at 159.766 123.571) (diameter 0) (color 0 0 0 0)
  )
  (junction (at 184.658 159.131) (diameter 0) (color 0 0 0 0)
  )
  (junction (at 148.971 94.361) (diameter 0) (color 0 0 0 0)
  )
  (junction (at 102.616 93.726) (diameter 0) (color 0 0 0 0)
  )
  (junction (at 169.926 126.111) (diameter 0) (color 0 0 0 0)
  )
  (junction (at 169.926 94.361) (diameter 0) (color 0 0 0 0)
  )
  (junction (at 90.551 93.726) (diameter 0) (color 0 0 0 0)
  )
  (junction (at 159.766 94.361) (diameter 0) (color 0 0 0 0)
  )
  (junction (at 114.046 93.726) (diameter 0) (color 0 0 0 0)
  )

  (no_connect (at 226.568 141.351))
  (no_connect (at 226.568 156.591))
  (no_connect (at 226.568 151.511))
  (no_connect (at 226.568 136.271))
  (no_connect (at 226.568 148.971))
  (no_connect (at 226.568 126.111))
  (no_connect (at 226.568 118.491))
  (no_connect (at 226.568 143.891))
  (no_connect (at 226.568 128.651))
  (no_connect (at 226.568 159.131))
  (no_connect (at 226.568 133.731))
  (no_connect (at 188.468 115.951))
  (no_connect (at 226.568 121.031))

  (wire (pts (xy 89.281 93.726) (xy 90.551 93.726))
    (stroke (width 0) (type default) (color 0 0 0 0))
  )
  (wire (pts (xy 178.308 131.191) (xy 188.468 131.191))
    (stroke (width 0) (type default) (color 0 0 0 0))
  )
  (wire (pts (xy 226.568 113.411) (xy 279.273 113.411))
    (stroke (width 0) (type default) (color 0 0 0 0))
  )
  (wire (pts (xy 188.468 159.131) (xy 184.658 159.131))
    (stroke (width 0) (type default) (color 0 0 0 0))
  )
  (wire (pts (xy 226.568 110.871) (xy 279.273 110.871))
    (stroke (width 0) (type default) (color 0 0 0 0))
  )
  (wire (pts (xy 169.926 94.361) (xy 169.926 102.743))
    (stroke (width 0) (type default) (color 0 0 0 0))
  )
  (wire (pts (xy 90.551 93.726) (xy 90.551 94.996))
    (stroke (width 0) (type default) (color 0 0 0 0))
  )
  (wire (pts (xy 169.926 107.823) (xy 169.926 126.111))
    (stroke (width 0) (type default) (color 0 0 0 0))
  )
  (wire (pts (xy 169.926 126.111) (xy 188.468 126.111))
    (stroke (width 0) (type default) (color 0 0 0 0))
  )
  (wire (pts (xy 194.056 189.23) (xy 195.961 189.23))
    (stroke (width 0) (type default) (color 0 0 0 0))
  )
  (wire (pts (xy 148.971 107.823) (xy 148.971 121.031))
    (stroke (width 0) (type default) (color 0 0 0 0))
  )
  (wire (pts (xy 148.082 133.731) (xy 149.352 133.731))
    (stroke (width 0) (type default) (color 0 0 0 0))
  )
  (wire (pts (xy 226.568 103.251) (xy 254.254 103.251))
    (stroke (width 0) (type default) (color 0 0 0 0))
  )
  (wire (pts (xy 184.658 159.131) (xy 184.658 161.671))
    (stroke (width 0) (type default) (color 0 0 0 0))
  )
  (wire (pts (xy 195.961 189.23) (xy 195.961 191.135))
    (stroke (width 0) (type default) (color 0 0 0 0))
  )
  (wire (pts (xy 159.766 94.361) (xy 169.926 94.361))
    (stroke (width 0) (type default) (color 0 0 0 0))
  )
  (wire (pts (xy 159.766 94.361) (xy 159.766 102.743))
    (stroke (width 0) (type default) (color 0 0 0 0))
  )
  (wire (pts (xy 226.568 94.361) (xy 279.273 94.361))
    (stroke (width 0) (type default) (color 0 0 0 0))
  )
  (wire (pts (xy 90.551 93.726) (xy 102.616 93.726))
    (stroke (width 0) (type default) (color 0 0 0 0))
  )
  (wire (pts (xy 136.271 121.031) (xy 148.971 121.031))
    (stroke (width 0) (type default) (color 0 0 0 0))
  )
  (wire (pts (xy 114.046 93.726) (xy 114.046 94.996))
    (stroke (width 0) (type default) (color 0 0 0 0))
  )
  (wire (pts (xy 147.701 94.361) (xy 148.971 94.361))
    (stroke (width 0) (type default) (color 0 0 0 0))
  )
  (wire (pts (xy 148.971 121.031) (xy 188.468 121.031))
    (stroke (width 0) (type default) (color 0 0 0 0))
  )
  (wire (pts (xy 259.334 103.251) (xy 279.273 103.251))
    (stroke (width 0) (type default) (color 0 0 0 0))
  )
  (wire (pts (xy 114.046 93.726) (xy 126.111 93.726))
    (stroke (width 0) (type default) (color 0 0 0 0))
  )
  (wire (pts (xy 188.468 156.591) (xy 184.658 156.591))
    (stroke (width 0) (type default) (color 0 0 0 0))
  )
  (wire (pts (xy 159.766 123.571) (xy 188.468 123.571))
    (stroke (width 0) (type default) (color 0 0 0 0))
  )
  (wire (pts (xy 126.111 93.726) (xy 126.111 94.996))
    (stroke (width 0) (type default) (color 0 0 0 0))
  )
  (wire (pts (xy 226.568 96.901) (xy 279.273 96.901))
    (stroke (width 0) (type default) (color 0 0 0 0))
  )
  (wire (pts (xy 136.271 123.571) (xy 159.766 123.571))
    (stroke (width 0) (type default) (color 0 0 0 0))
  )
  (wire (pts (xy 165.481 133.731) (xy 188.468 133.731))
    (stroke (width 0) (type default) (color 0 0 0 0))
  )
  (wire (pts (xy 148.971 94.361) (xy 159.766 94.361))
    (stroke (width 0) (type default) (color 0 0 0 0))
  )
  (wire (pts (xy 159.766 107.823) (xy 159.766 123.571))
    (stroke (width 0) (type default) (color 0 0 0 0))
  )
  (wire (pts (xy 184.658 156.591) (xy 184.658 159.131))
    (stroke (width 0) (type default) (color 0 0 0 0))
  )
  (wire (pts (xy 102.616 93.726) (xy 102.616 94.996))
    (stroke (width 0) (type default) (color 0 0 0 0))
  )
  (wire (pts (xy 169.926 126.111) (xy 136.271 126.111))
    (stroke (width 0) (type default) (color 0 0 0 0))
  )
  (wire (pts (xy 169.926 94.361) (xy 188.468 94.361))
    (stroke (width 0) (type default) (color 0 0 0 0))
  )
  (wire (pts (xy 154.432 133.731) (xy 157.861 133.731))
    (stroke (width 0) (type default) (color 0 0 0 0))
  )
  (wire (pts (xy 148.971 94.361) (xy 148.971 102.743))
    (stroke (width 0) (type default) (color 0 0 0 0))
  )
  (wire (pts (xy 136.271 118.491) (xy 188.468 118.491))
    (stroke (width 0) (type default) (color 0 0 0 0))
  )
  (wire (pts (xy 102.616 93.726) (xy 114.046 93.726))
    (stroke (width 0) (type default) (color 0 0 0 0))
  )
  (wire (pts (xy 226.568 105.791) (xy 258.064 105.791))
    (stroke (width 0) (type default) (color 0 0 0 0))
  )
  (wire (pts (xy 178.308 128.651) (xy 188.468 128.651))
    (stroke (width 0) (type default) (color 0 0 0 0))
  )
  (wire (pts (xy 263.144 105.791) (xy 279.273 105.791))
    (stroke (width 0) (type default) (color 0 0 0 0))
  )

  (text "M.2 22x80mm NVMe mechanical model" (at 207.391 184.912 0)
    (effects (font (size 1.4986 1.4986)) (justify left bottom))
  )
  (text "place close to\npin 2 of \nM.2 connector" (at 84.201 91.186 0)
    (effects (font (size 1.27 1.27)) (justify left bottom))
  )
  (text "place close to\npin 72 of\nM.2 connector" (at 119.761 91.821 0)
    (effects (font (size 1.27 1.27)) (justify left bottom))
  )
  (text "M.2 key M" (at 194.691 77.216 0)
    (effects (font (size 2.9972 2.9972) (thickness 0.5994) bold) (justify left bottom))
  )
  (text "place close to\npin 16 and 14 of \nM.2 connector" (at 101.346 114.681 0)
    (effects (font (size 1.27 1.27)) (justify left bottom))
  )
  (text "Text" (at 67.7926 1253.8202 0)
    (effects (font (size 1.524 1.524)) (justify left bottom))
  )
  (text "Text" (at 67.7926 1253.8202 0)
    (effects (font (size 1.524 1.524)) (justify left bottom))
  )

  (label "C_PCIE0_TX0_P" (at 230.378 103.251 0)
    (effects (font (size 1.524 1.524)) (justify left bottom))
  )
  (label "C_PCIE0_TX0_N" (at 230.378 105.791 0)
    (effects (font (size 1.524 1.524)) (justify left bottom))
  )

  (global_label "3V3_SYS" (shape input) (at 147.701 94.361 180) (fields_autoplaced)
    (effects (font (size 1.27 1.27)) (justify right))
    (property "Intersheet References" "${INTERSHEET_REFS}" (id 0) (at 59.436 50.546 0)
      (effects (font (size 1.27 1.27)) hide)
    )
  )
  (global_label "3V3_SYS" (shape input) (at 148.082 133.731 180) (fields_autoplaced)
    (effects (font (size 1.27 1.27)) (justify right))
    (property "Intersheet References" "${INTERSHEET_REFS}" (id 0) (at 137.7749 133.6516 0)
      (effects (font (size 1.27 1.27)) (justify right) hide)
    )
  )
  (global_label "PCIE0_TX_P" (shape input) (at 279.273 103.251 0) (fields_autoplaced)
    (effects (font (size 1.27 1.27)) (justify left))
    (property "Intersheet References" "${INTERSHEET_REFS}" (id 0) (at 58.293 31.496 0)
      (effects (font (size 1.27 1.27)) hide)
    )
  )
  (global_label "PCIE0_WAKE_N" (shape output) (at 136.271 118.491 180) (fields_autoplaced)
    (effects (font (size 1.27 1.27)) (justify right))
    (property "Intersheet References" "${INTERSHEET_REFS}" (id 0) (at 59.436 51.816 0)
      (effects (font (size 1.27 1.27)) hide)
    )
  )
  (global_label "PCIE0_TX_N" (shape input) (at 279.273 105.791 0) (fields_autoplaced)
    (effects (font (size 1.27 1.27)) (justify left))
    (property "Intersheet References" "${INTERSHEET_REFS}" (id 0) (at 58.293 31.496 0)
      (effects (font (size 1.27 1.27)) hide)
    )
  )
  (global_label "PCIE0_RX_N" (shape output) (at 279.273 113.411 0) (fields_autoplaced)
    (effects (font (size 1.27 1.27)) (justify left))
    (property "Intersheet References" "${INTERSHEET_REFS}" (id 0) (at 58.293 31.496 0)
      (effects (font (size 1.27 1.27)) hide)
    )
  )
  (global_label "PCIE0_REFCLK_N" (shape input) (at 279.273 96.901 0) (fields_autoplaced)
    (effects (font (size 1.27 1.27)) (justify left))
    (property "Intersheet References" "${INTERSHEET_REFS}" (id 0) (at 58.293 30.226 0)
      (effects (font (size 1.27 1.27)) hide)
    )
  )
  (global_label "PCIE0_RST_N" (shape input) (at 136.271 123.571 180) (fields_autoplaced)
    (effects (font (size 1.27 1.27)) (justify right))
    (property "Intersheet References" "${INTERSHEET_REFS}" (id 0) (at 59.436 51.816 0)
      (effects (font (size 1.27 1.27)) hide)
    )
  )
  (global_label "PCIE0_RX_P" (shape output) (at 279.273 110.871 0) (fields_autoplaced)
    (effects (font (size 1.27 1.27)) (justify left))
    (property "Intersheet References" "${INTERSHEET_REFS}" (id 0) (at 58.293 31.496 0)
      (effects (font (size 1.27 1.27)) hide)
    )
  )
  (global_label "M2_ALERT" (shape output) (at 136.271 126.111 180) (fields_autoplaced)
    (effects (font (size 1.27 1.27)) (justify right))
    (property "Intersheet References" "${INTERSHEET_REFS}" (id 0) (at 59.436 46.736 0)
      (effects (font (size 1.27 1.27)) hide)
    )
  )
  (global_label "PCIE0_CLKREQ_N" (shape output) (at 136.271 121.031 180) (fields_autoplaced)
    (effects (font (size 1.27 1.27)) (justify right))
    (property "Intersheet References" "${INTERSHEET_REFS}" (id 0) (at 59.436 51.816 0)
      (effects (font (size 1.27 1.27)) hide)
    )
  )
  (global_label "PCIE0_REFCLK_P" (shape input) (at 279.273 94.361 0) (fields_autoplaced)
    (effects (font (size 1.27 1.27)) (justify left))
    (property "Intersheet References" "${INTERSHEET_REFS}" (id 0) (at 58.293 30.226 0)
      (effects (font (size 1.27 1.27)) hide)
    )
  )
  (global_label "3V3_SYS" (shape input) (at 89.281 93.726 180) (fields_autoplaced)
    (effects (font (size 1.27 1.27)) (justify right))
    (property "Intersheet References" "${INTERSHEET_REFS}" (id 0) (at 59.436 50.546 0)
      (effects (font (size 1.27 1.27)) hide)
    )
  )

  (symbol (lib_id "sa800u-baseboard-hw:Bus_M.2_MDT580M01001") (at 188.468 94.361 0) (unit 1)
    (in_bom yes) (on_board yes) (fields_autoplaced)
    (property "Reference" "U15" (id 0) (at 207.518 86.106 0))
    (property "Value" "Bus_M.2_MDT580M01001" (id 1) (at 240.538 99.441 0)
      (effects (font (size 1.27 1.27) (thickness 0.15)) (justify left bottom) hide)
    )
    (property "Footprint" "sa800u-baseboard-hw-footprints:Bus_M.2_Socket_Key_M_Amphenol_MDT580M01001" (id 2) (at 240.538 101.981 0)
      (effects (font (size 1.27 1.27) (thickness 0.15)) (justify left bottom) hide)
    )
    (property "Datasheet" "https://cdn.amphenol-cs.com/media/wysiwyg/files/documentation/gs-12-1248.pdf" (id 3) (at 240.538 104.521 0)
      (effects (font (size 1.27 1.27) (thickness 0.15)) (justify left bottom) hide)
    )
    (property "MPN" "MDT580M01001" (id 4) (at 207.518 88.646 0)
      (effects (font (size 1.27 1.27) (thickness 0.15)))
    )
    (property "Manufacturer" "Amphenol" (id 5) (at 240.538 109.601 0)
      (effects (font (size 1.27 1.27) (thickness 0.15)) (justify left bottom) hide)
    )
    (property "Author" "Antmicro" (id 6) (at 240.538 112.141 0)
      (effects (font (size 1.27 1.27) (thickness 0.15)) (justify left bottom) hide)
    )
    (property "License" "Apache-2.0" (id 7) (at 240.538 114.681 0)
      (effects (font (size 1.27 1.27) (thickness 0.15)) (justify left bottom) hide)
    )
    (pin "1")
    (pin "10")
    (pin "11")
    (pin "12")
    (pin "13")
    (pin "14")
    (pin "15")
    (pin "16")
    (pin "17")
    (pin "18")
    (pin "19")
    (pin "2")
    (pin "20")
    (pin "21")
    (pin "22")
    (pin "23")
    (pin "24")
    (pin "25")
    (pin "26")
    (pin "27")
    (pin "28")
    (pin "29")
    (pin "3")
    (pin "30")
    (pin "31")
    (pin "32")
    (pin "33")
    (pin "34")
    (pin "35")
    (pin "36")
    (pin "37")
    (pin "38")
    (pin "39")
    (pin "4")
    (pin "40")
    (pin "41")
    (pin "42")
    (pin "43")
    (pin "44")
    (pin "45")
    (pin "46")
    (pin "47")
    (pin "48")
    (pin "49")
    (pin "5")
    (pin "50")
    (pin "51")
    (pin "52")
    (pin "53")
    (pin "54")
    (pin "55")
    (pin "56")
    (pin "57")
    (pin "58")
    (pin "6")
    (pin "67")
    (pin "68")
    (pin "69")
    (pin "7")
    (pin "70")
    (pin "71")
    (pin "72")
    (pin "73")
    (pin "74")
    (pin "75")
    (pin "8")
    (pin "9")
    (pin "SH1")
    (pin "SH2")
  )

  (symbol (lib_id "sa800u-baseboard-hw:R_10k_0402") (at 148.971 102.743 270) (unit 1)
    (in_bom yes) (on_board yes) (fields_autoplaced)
    (property "Reference" "R90" (id 0) (at 150.876 104.013 90)
      (effects (font (size 1.524 1.524)) (justify left))
    )
    (property "Value" "R_10k_0402" (id 1) (at 145.161 102.743 0)
      (effects (font (size 1.524 1.524)) hide)
    )
    (property "Footprint" "sa800u-baseboard-hw-footprints:R_0402_1005Metric" (id 2) (at 154.051 107.823 0)
      (effects (font (size 1.524 1.524)) (justify left) hide)
    )
    (property "Datasheet" "https://www.bourns.com/docs/product-datasheets/cr.pdf" (id 3) (at 148.971 102.743 0)
      (effects (font (size 1.27 1.27)) hide)
    )
    (property "Manufacturer" "Bourns" (id 4) (at 159.131 107.823 0)
      (effects (font (size 1.524 1.524)) (justify left) hide)
    )
    (property "MPN" "CR0402-FX-1002GLF" (id 5) (at 156.591 107.823 0)
      (effects (font (size 1.524 1.524)) (justify left) hide)
    )
    (property "Val" "10k" (id 6) (at 150.876 107.1879 90)
      (effects (font (size 1.27 1.27)) (justify left))
    )
    (property "License" "Apache-2.0" (id 7) (at 123.571 123.063 0)
      (effects (font (size 1.27 1.27) (thickness 0.15)) (justify left bottom) hide)
    )
    (property "Author" "Antmicro" (id 8) (at 121.031 123.063 0)
      (effects (font (size 1.27 1.27) (thickness 0.15)) (justify left bottom) hide)
    )
    (property "Tolerance" "1%" (id 9) (at 138.811 123.063 0)
      (effects (font (size 1.27 1.27)) (justify left bottom) hide)
    )
    (pin "1")
    (pin "2")
  )

  (symbol (lib_id "sa800u-baseboard-hw:R_10k_0402") (at 159.766 102.743 270) (unit 1)
    (in_bom yes) (on_board yes) (fields_autoplaced)
    (property "Reference" "R91" (id 0) (at 162.306 104.013 90)
      (effects (font (size 1.524 1.524)) (justify left))
    )
    (property "Value" "R_10k_0402" (id 1) (at 155.956 102.743 0)
      (effects (font (size 1.524 1.524)) hide)
    )
    (property "Footprint" "sa800u-baseboard-hw-footprints:R_0402_1005Metric" (id 2) (at 164.846 107.823 0)
      (effects (font (size 1.524 1.524)) (justify left) hide)
    )
    (property "Datasheet" "https://www.bourns.com/docs/product-datasheets/cr.pdf" (id 3) (at 159.766 102.743 0)
      (effects (font (size 1.27 1.27)) hide)
    )
    (property "Manufacturer" "Bourns" (id 4) (at 169.926 107.823 0)
      (effects (font (size 1.524 1.524)) (justify left) hide)
    )
    (property "MPN" "CR0402-FX-1002GLF" (id 5) (at 167.386 107.823 0)
      (effects (font (size 1.524 1.524)) (justify left) hide)
    )
    (property "Val" "10k" (id 6) (at 162.306 107.1879 90)
      (effects (font (size 1.27 1.27)) (justify left))
    )
    (property "License" "Apache-2.0" (id 7) (at 134.366 123.063 0)
      (effects (font (size 1.27 1.27) (thickness 0.15)) (justify left bottom) hide)
    )
    (property "Author" "Antmicro" (id 8) (at 131.826 123.063 0)
      (effects (font (size 1.27 1.27) (thickness 0.15)) (justify left bottom) hide)
    )
    (property "Tolerance" "1%" (id 9) (at 149.606 123.063 0)
      (effects (font (size 1.27 1.27)) (justify left bottom) hide)
    )
    (pin "1")
    (pin "2")
  )

  (symbol (lib_id "sa800u-baseboard-hw:R_10k_0402") (at 169.926 102.743 270) (unit 1)
    (in_bom yes) (on_board yes) (fields_autoplaced)
    (property "Reference" "R93" (id 0) (at 172.466 104.013 90)
      (effects (font (size 1.524 1.524)) (justify left))
    )
    (property "Value" "R_10k_0402" (id 1) (at 166.116 102.743 0)
      (effects (font (size 1.524 1.524)) hide)
    )
    (property "Footprint" "sa800u-baseboard-hw-footprints:R_0402_1005Metric" (id 2) (at 175.006 107.823 0)
      (effects (font (size 1.524 1.524)) (justify left) hide)
    )
    (property "Datasheet" "https://www.bourns.com/docs/product-datasheets/cr.pdf" (id 3) (at 169.926 102.743 0)
      (effects (font (size 1.27 1.27)) hide)
    )
    (property "Manufacturer" "Bourns" (id 4) (at 180.086 107.823 0)
      (effects (font (size 1.524 1.524)) (justify left) hide)
    )
    (property "MPN" "CR0402-FX-1002GLF" (id 5) (at 177.546 107.823 0)
      (effects (font (size 1.524 1.524)) (justify left) hide)
    )
    (property "Val" "10k" (id 6) (at 172.466 107.1879 90)
      (effects (font (size 1.27 1.27)) (justify left))
    )
    (property "License" "Apache-2.0" (id 7) (at 144.526 123.063 0)
      (effects (font (size 1.27 1.27) (thickness 0.15)) (justify left bottom) hide)
    )
    (property "Author" "Antmicro" (id 8) (at 141.986 123.063 0)
      (effects (font (size 1.27 1.27) (thickness 0.15)) (justify left bottom) hide)
    )
    (property "Tolerance" "1%" (id 9) (at 159.766 123.063 0)
      (effects (font (size 1.27 1.27)) (justify left bottom) hide)
    )
    (pin "1")
    (pin "2")
  )

  (symbol (lib_id "sa800u-baseboard-hw:R_220R_0402") (at 149.352 133.731 0) (unit 1)
    (in_bom yes) (on_board yes)
    (property "Reference" "R92" (id 0) (at 151.765 136.525 0)
      (effects (font (size 1.524 1.524)))
    )
    (property "Value" "R_220R_0402" (id 1) (at 149.352 137.541 0)
      (effects (font (size 1.524 1.524)) hide)
    )
    (property "Footprint" "sa800u-baseboard-hw-footprints:R_0402_1005Metric" (id 2) (at 154.432 128.651 0)
      (effects (font (size 1.524 1.524)) (justify left) hide)
    )
    (property "Datasheet" "https://www.bourns.com/docs/product-datasheets/cr.pdf" (id 3) (at 149.352 133.731 0)
      (effects (font (size 1.27 1.27)) hide)
    )
    (property "Manufacturer" "Bourns" (id 4) (at 154.432 123.571 0)
      (effects (font (size 1.524 1.524)) (justify left) hide)
    )
    (property "MPN" "CR0402-FX-2200GLF" (id 5) (at 154.432 126.111 0)
      (effects (font (size 1.524 1.524)) (justify left) hide)
    )
    (property "Val" "220R" (id 6) (at 151.765 139.065 0))
    (property "License" "Apache-2.0" (id 7) (at 169.672 159.131 0)
      (effects (font (size 1.27 1.27) (thickness 0.15)) (justify left bottom) hide)
    )
    (property "Author" "Antmicro" (id 8) (at 169.672 161.671 0)
      (effects (font (size 1.27 1.27) (thickness 0.15)) (justify left bottom) hide)
    )
    (property "Tolerance" "1%" (id 9) (at 169.672 143.891 0)
      (effects (font (size 1.27 1.27)) (justify left bottom) hide)
    )
    (pin "1")
    (pin "2")
  )

  (symbol (lib_id "sa800u-baseboard-hw:C_1u_0402") (at 114.046 94.996 270) (unit 1)
    (in_bom yes) (on_board yes) (fields_autoplaced)
    (property "Reference" "C113" (id 0) (at 116.586 96.2723 90)
      (effects (font (size 1.524 1.524)) (justify left))
    )
    (property "Value" "C_1u_0402" (id 1) (at 110.236 94.996 0)
      (effects (font (size 1.524 1.524)) hide)
    )
    (property "Footprint" "sa800u-baseboard-hw-footprints:C_0402_1005Metric" (id 2) (at 119.126 100.076 0)
      (effects (font (size 1.524 1.524)) (justify left) hide)
    )
    (property "Datasheet" " " (id 3) (at 114.046 94.996 0)
      (effects (font (size 1.27 1.27)) hide)
    )
    (property "Manufacturer" "TDK" (id 4) (at 124.206 100.076 0)
      (effects (font (size 1.524 1.524)) (justify left) hide)
    )
    (property "MPN" "C1005X6S1A105K050BC" (id 5) (at 121.666 100.076 0)
      (effects (font (size 1.524 1.524)) (justify left) hide)
    )
    (property "Val" "1u" (id 6) (at 116.586 99.4472 90)
      (effects (font (size 1.27 1.27)) (justify left))
    )
    (property "License" "Apache-2.0" (id 7) (at 91.186 115.316 0)
      (effects (font (size 1.27 1.27) (thickness 0.15)) (justify left bottom) hide)
    )
    (property "Author" "Antmicro" (id 8) (at 88.646 115.316 0)
      (effects (font (size 1.27 1.27) (thickness 0.15)) (justify left bottom) hide)
    )
    (property "Voltage" "" (id 9) (at 86.106 115.316 0)
      (effects (font (size 1.27 1.27)) (justify left bottom) hide)
    )
    (property "Dielectric" "" (id 10) (at 83.566 115.316 0)
      (effects (font (size 1.27 1.27)) (justify left bottom) hide)
    )
    (pin "1")
    (pin "2")
  )

  (symbol (lib_id "sa800u-baseboard-hw:GND") (at 114.046 100.076 0) (unit 1)
    (in_bom yes) (on_board yes) (fields_autoplaced)
    (property "Reference" "#PWR0184" (id 0) (at 114.046 106.426 0)
      (effects (font (size 1.27 1.27)) hide)
    )
    (property "Value" "GND" (id 1) (at 114.046 105.156 0))
    (property "Footprint" "" (id 2) (at 114.046 100.076 0)
      (effects (font (size 1.27 1.27)) hide)
    )
    (property "Datasheet" "" (id 3) (at 114.046 100.076 0)
      (effects (font (size 1.27 1.27)) hide)
    )
    (property "Author" "Antmicro" (id 4) (at 122.936 107.696 0)
      (effects (font (size 1.27 1.27) (thickness 0.15)) (justify left bottom) hide)
    )
    (property "License" "Apache-2.0" (id 5) (at 122.936 110.236 0)
      (effects (font (size 1.27 1.27) (thickness 0.15)) (justify left bottom) hide)
    )
    (pin "1")
  )

  (symbol (lib_id "sa800u-baseboard-hw:C_100n_0402") (at 254.254 103.251 0) (unit 1)
    (in_bom yes) (on_board yes)
    (property "Reference" "C115" (id 0) (at 252.984 101.981 0)
      (effects (font (size 1.524 1.524)))
    )
    (property "Value" "C_100n_0402" (id 1) (at 254.254 107.061 0)
      (effects (font (size 1.524 1.524)) hide)
    )
    (property "Footprint" "sa800u-baseboard-hw-footprints:C_0402_1005Metric" (id 2) (at 259.334 98.171 0)
      (effects (font (size 1.524 1.524)) (justify left) hide)
    )
    (property "Datasheet" "https://search.murata.co.jp/Ceramy/image/img/A01X/G101/ENG/GRM155R61H104KE14-01.pdf" (id 3) (at 254.254 103.251 0)
      (effects (font (size 1.27 1.27)) hide)
    )
    (property "Manufacturer" "Murata" (id 4) (at 259.334 93.091 0)
      (effects (font (size 1.524 1.524)) (justify left) hide)
    )
    (property "MPN" "GRM155R61H104KE14D" (id 5) (at 259.334 95.631 0)
      (effects (font (size 1.524 1.524)) (justify left) hide)
    )
    (property "Val" "100n" (id 6) (at 252.984 104.521 0))
    (property "License" "Apache-2.0" (id 7) (at 274.574 126.111 0)
      (effects (font (size 1.27 1.27) (thickness 0.15)) (justify left bottom) hide)
    )
    (property "Author" "Antmicro" (id 8) (at 274.574 128.651 0)
      (effects (font (size 1.27 1.27) (thickness 0.15)) (justify left bottom) hide)
    )
    (property "Voltage" "50V" (id 9) (at 274.574 131.191 0)
      (effects (font (size 1.27 1.27)) (justify left bottom) hide)
    )
    (property "Dielectric" "X5R" (id 10) (at 274.574 133.731 0)
      (effects (font (size 1.27 1.27)) (justify left bottom) hide)
    )
    (pin "1")
    (pin "2")
  )

  (symbol (lib_id "sa800u-baseboard-hw:C_100n_0402") (at 258.064 105.791 0) (unit 1)
    (in_bom yes) (on_board yes)
    (property "Reference" "C116" (id 0) (at 264.414 104.648 0)
      (effects (font (size 1.524 1.524)))
    )
    (property "Value" "C_100n_0402" (id 1) (at 258.064 109.601 0)
      (effects (font (size 1.524 1.524)) hide)
    )
    (property "Footprint" "sa800u-baseboard-hw-footprints:C_0402_1005Metric" (id 2) (at 263.144 100.711 0)
      (effects (font (size 1.524 1.524)) (justify left) hide)
    )
    (property "Datasheet" "https://search.murata.co.jp/Ceramy/image/img/A01X/G101/ENG/GRM155R61H104KE14-01.pdf" (id 3) (at 258.064 105.791 0)
      (effects (font (size 1.27 1.27)) hide)
    )
    (property "Manufacturer" "Murata" (id 4) (at 263.144 95.631 0)
      (effects (font (size 1.524 1.524)) (justify left) hide)
    )
    (property "MPN" "GRM155R61H104KE14D" (id 5) (at 263.144 98.171 0)
      (effects (font (size 1.524 1.524)) (justify left) hide)
    )
    (property "Val" "100n" (id 6) (at 264.541 106.934 0))
    (property "License" "Apache-2.0" (id 7) (at 278.384 128.651 0)
      (effects (font (size 1.27 1.27) (thickness 0.15)) (justify left bottom) hide)
    )
    (property "Author" "Antmicro" (id 8) (at 278.384 131.191 0)
      (effects (font (size 1.27 1.27) (thickness 0.15)) (justify left bottom) hide)
    )
    (property "Voltage" "50V" (id 9) (at 278.384 133.731 0)
      (effects (font (size 1.27 1.27)) (justify left bottom) hide)
    )
    (property "Dielectric" "X5R" (id 10) (at 278.384 136.271 0)
      (effects (font (size 1.27 1.27)) (justify left bottom) hide)
    )
    (pin "1")
    (pin "2")
  )

  (symbol (lib_id "sa800u-baseboard-hw:Spacer_H4.0mm_9774040151") (at 194.056 189.23 180) (unit 1)
    (in_bom yes) (on_board yes) (fields_autoplaced)
    (property "Reference" "SP5" (id 0) (at 188.976 180.975 0)
      (effects (font (size 1.524 1.524)))
    )
    (property "Value" "Spacer_H4.0mm_9774040151" (id 1) (at 188.976 183.515 0)
      (effects (font (size 1.27 1.27) (thickness 0.15)) hide)
    )
    (property "Footprint" "sa800u-baseboard-hw-footprints:Spacer_SMD_M2.5_H4mm_Wurth_9774040151" (id 2) (at 171.196 181.61 0)
      (effects (font (size 1.27 1.27) (thickness 0.15)) (justify left bottom) hide)
    )
    (property "Datasheet" "https://www.we-online.com/components/products/datasheet/9774040151R.pdf" (id 3) (at 171.196 179.07 0)
      (effects (font (size 1.27 1.27) (thickness 0.15)) (justify left bottom) hide)
    )
    (property "Manufacturer" "Würth Elektronik" (id 4) (at 171.196 176.53 0)
      (effects (font (size 1.27 1.27) (thickness 0.15)) (justify left bottom) hide)
    )
    (property "MPN" "9774040151R" (id 5) (at 188.976 183.515 0)
      (effects (font (size 1.27 1.27) (thickness 0.15)))
    )
    (property "Author" "Antmicro" (id 6) (at 171.196 171.45 0)
      (effects (font (size 1.27 1.27) (thickness 0.15)) (justify left bottom) hide)
    )
    (property "License" "Apache-2.0" (id 7) (at 171.196 168.91 0)
      (effects (font (size 1.27 1.27) (thickness 0.15)) (justify left bottom) hide)
    )
    (pin "1")
  )

  (symbol (lib_id "sa800u-baseboard-hw:GND") (at 195.961 191.135 0) (unit 1)
    (in_bom yes) (on_board yes) (fields_autoplaced)
    (property "Reference" "#PWR0187" (id 0) (at 195.961 197.485 0)
      (effects (font (size 1.27 1.27)) hide)
    )
    (property "Value" "GND" (id 1) (at 195.961 196.215 0))
    (property "Footprint" "" (id 2) (at 195.961 191.135 0)
      (effects (font (size 1.27 1.27)) hide)
    )
    (property "Datasheet" "" (id 3) (at 195.961 191.135 0)
      (effects (font (size 1.27 1.27)) hide)
    )
    (property "Author" "Antmicro" (id 4) (at 204.851 198.755 0)
      (effects (font (size 1.27 1.27) (thickness 0.15)) (justify left bottom) hide)
    )
    (property "License" "Apache-2.0" (id 5) (at 204.851 201.295 0)
      (effects (font (size 1.27 1.27) (thickness 0.15)) (justify left bottom) hide)
    )
    (pin "1")
  )

  (symbol (lib_id "sa800u-baseboard-hw:GND") (at 184.658 161.671 0) (unit 1)
    (in_bom yes) (on_board yes) (fields_autoplaced)
    (property "Reference" "#PWR0186" (id 0) (at 184.658 168.021 0)
      (effects (font (size 1.27 1.27)) hide)
    )
    (property "Value" "GND" (id 1) (at 184.658 166.116 0))
    (property "Footprint" "" (id 2) (at 184.658 161.671 0)
      (effects (font (size 1.27 1.27)) hide)
    )
    (property "Datasheet" "" (id 3) (at 184.658 161.671 0)
      (effects (font (size 1.27 1.27)) hide)
    )
    (property "Author" "Antmicro" (id 4) (at 193.548 169.291 0)
      (effects (font (size 1.27 1.27) (thickness 0.15)) (justify left bottom) hide)
    )
    (property "License" "Apache-2.0" (id 5) (at 193.548 171.831 0)
      (effects (font (size 1.27 1.27) (thickness 0.15)) (justify left bottom) hide)
    )
    (pin "1")
  )

  (symbol (lib_id "sa800u-baseboard-hw:TP_0.75mm_SMD") (at 178.308 128.651 180) (unit 1)
    (in_bom yes) (on_board yes)
    (property "Reference" "TP42" (id 0) (at 170.18 128.651 0))
    (property "Value" "TP_0.75mm_SMD" (id 1) (at 178.308 126.111 0)
      (effects (font (size 1.27 1.27)) hide)
    )
    (property "Footprint" "sa800u-baseboard-hw-footprints:TP_SMD_0.75mm" (id 2) (at 173.228 133.731 0)
      (effects (font (size 1.524 1.524)) (justify left) hide)
    )
    (property "Datasheet" "" (id 3) (at 173.228 136.271 0)
      (effects (font (size 1.524 1.524)) (justify left) hide)
    )
    (property "MPN" "" (id 4) (at 160.528 113.411 0)
      (effects (font (size 1.27 1.27) (thickness 0.15)) (justify left bottom) hide)
    )
    (property "Manufacturer" "" (id 5) (at 160.528 110.871 0)
      (effects (font (size 1.27 1.27) (thickness 0.15)) (justify left bottom) hide)
    )
    (property "Author" "Antmicro" (id 6) (at 160.528 108.331 0)
      (effects (font (size 1.27 1.27) (thickness 0.15)) (justify left bottom) hide)
    )
    (property "License" "Apache-2.0" (id 7) (at 160.528 105.791 0)
      (effects (font (size 1.27 1.27) (thickness 0.15)) (justify left bottom) hide)
    )
    (pin "1")
  )

  (symbol (lib_id "sa800u-baseboard-hw:TP_0.75mm_SMD") (at 178.308 131.191 180) (unit 1)
    (in_bom yes) (on_board yes) (fields_autoplaced)
    (property "Reference" "TP43" (id 0) (at 172.593 131.1909 0)
      (effects (font (size 1.27 1.27)) (justify left))
    )
    (property "Value" "TP_0.75mm_SMD" (id 1) (at 178.308 128.651 0)
      (effects (font (size 1.27 1.27)) hide)
    )
    (property "Footprint" "sa800u-baseboard-hw-footprints:TP_SMD_0.75mm" (id 2) (at 173.228 136.271 0)
      (effects (font (size 1.524 1.524)) (justify left) hide)
    )
    (property "Datasheet" "" (id 3) (at 173.228 138.811 0)
      (effects (font (size 1.524 1.524)) (justify left) hide)
    )
    (property "MPN" "" (id 4) (at 160.528 115.951 0)
      (effects (font (size 1.27 1.27) (thickness 0.15)) (justify left bottom) hide)
    )
    (property "Manufacturer" "" (id 5) (at 160.528 113.411 0)
      (effects (font (size 1.27 1.27) (thickness 0.15)) (justify left bottom) hide)
    )
    (property "Author" "Antmicro" (id 6) (at 160.528 110.871 0)
      (effects (font (size 1.27 1.27) (thickness 0.15)) (justify left bottom) hide)
    )
    (property "License" "Apache-2.0" (id 7) (at 160.528 108.331 0)
      (effects (font (size 1.27 1.27) (thickness 0.15)) (justify left bottom) hide)
    )
    (pin "1")
  )

  (symbol (lib_id "sa800u-baseboard-hw:Mech_M2_2280_H4mm") (at 213.106 186.309 0) (unit 1)
    (in_bom yes) (on_board yes) (fields_autoplaced)
    (property "Reference" "M2" (id 0) (at 224.536 188.2139 0)
      (effects (font (size 1.27 1.27)) (justify left))
    )
    (property "Value" "Mech_M2_2280_H4mm" (id 1) (at 224.536 190.7539 0)
      (effects (font (size 1.27 1.27)) (justify left))
    )
    (property "Footprint" "sa800u-baseboard-hw-footprints:Mech_M2_2280_H4mm" (id 2) (at 238.506 191.389 0)
      (effects (font (size 1.27 1.27) (thickness 0.15)) (justify left bottom) hide)
    )
    (property "Datasheet" "" (id 3) (at 238.506 193.929 0)
      (effects (font (size 1.27 1.27) (thickness 0.15)) (justify left bottom) hide)
    )
    (property "Manufacturer" "" (id 4) (at 213.106 186.309 0)
      (effects (font (size 1.27 1.27)) hide)
    )
    (property "MPN" "" (id 5) (at 213.106 186.309 0)
      (effects (font (size 1.27 1.27)) hide)
    )
    (property "Author" "Antmicro" (id 6) (at 238.506 196.469 0)
      (effects (font (size 1.27 1.27) (thickness 0.15)) (justify left bottom) hide)
    )
    (property "License" "Apache-2.0" (id 7) (at 238.506 199.009 0)
      (effects (font (size 1.27 1.27) (thickness 0.15)) (justify left bottom) hide)
    )
    (property "DNP" "DNP" (id 8) (at 213.106 186.309 0)
      (effects (font (size 1.27 1.27)) hide)
    )
  )

  (symbol (lib_id "sa800u-baseboard-hw:LED_G_0603_KP-1608ZGC") (at 157.861 133.731 0) (unit 1)
    (in_bom yes) (on_board yes)
    (property "Reference" "D21" (id 0) (at 161.798 136.779 0)
      (effects (font (size 1.524 1.524)))
    )
    (property "Value" "KP-1608EC" (id 1) (at 156.591 127.8636 0)
      (effects (font (size 1.524 1.524)) hide)
    )
    (property "Footprint" "sa800u-baseboard-hw-footprints:LED_0603_1608Metric_G" (id 2) (at 180.721 143.891 0)
      (effects (font (size 1.27 1.27) (thickness 0.15)) (justify left bottom) hide)
    )
    (property "Datasheet" "https://www.farnell.com/datasheets/2045914.pdf" (id 3) (at 180.721 146.431 0)
      (effects (font (size 1.27 1.27) (thickness 0.15)) (justify left bottom) hide)
    )
    (property "MPN" "KP-1608ZGC" (id 4) (at 180.721 148.971 0)
      (effects (font (size 1.27 1.27) (thickness 0.15)) (justify left bottom) hide)
    )
    (property "Manufacturer" "Kingbright" (id 5) (at 180.721 151.511 0)
      (effects (font (size 1.27 1.27) (thickness 0.15)) (justify left bottom) hide)
    )
    (property "Author" "Antmicro" (id 6) (at 180.721 154.051 0)
      (effects (font (size 1.27 1.27) (thickness 0.15)) (justify left bottom) hide)
    )
    (property "License" "Apache-2.0" (id 7) (at 180.721 156.591 0)
      (effects (font (size 1.27 1.27) (thickness 0.15)) (justify left bottom) hide)
    )
    (pin "1")
    (pin "2")
  )

  (symbol (lib_id "sa800u-baseboard-hw:C_1u_0402") (at 102.616 94.996 270) (unit 1)
    (in_bom yes) (on_board yes) (fields_autoplaced)
    (property "Reference" "C112" (id 0) (at 105.283 96.2723 90)
      (effects (font (size 1.524 1.524)) (justify left))
    )
    (property "Value" "C_1u_0402" (id 1) (at 98.806 94.996 0)
      (effects (font (size 1.524 1.524)) hide)
    )
    (property "Footprint" "sa800u-baseboard-hw-footprints:C_0402_1005Metric" (id 2) (at 107.696 100.076 0)
      (effects (font (size 1.524 1.524)) (justify left) hide)
    )
    (property "Datasheet" " " (id 3) (at 102.616 94.996 0)
      (effects (font (size 1.27 1.27)) hide)
    )
    (property "Manufacturer" "TDK" (id 4) (at 112.776 100.076 0)
      (effects (font (size 1.524 1.524)) (justify left) hide)
    )
    (property "MPN" "C1005X6S1A105K050BC" (id 5) (at 110.236 100.076 0)
      (effects (font (size 1.524 1.524)) (justify left) hide)
    )
    (property "Val" "1u" (id 6) (at 105.283 99.4472 90)
      (effects (font (size 1.27 1.27)) (justify left))
    )
    (property "License" "Apache-2.0" (id 7) (at 79.756 115.316 0)
      (effects (font (size 1.27 1.27) (thickness 0.15)) (justify left bottom) hide)
    )
    (property "Author" "Antmicro" (id 8) (at 77.216 115.316 0)
      (effects (font (size 1.27 1.27) (thickness 0.15)) (justify left bottom) hide)
    )
    (property "Voltage" "" (id 9) (at 74.676 115.316 0)
      (effects (font (size 1.27 1.27)) (justify left bottom) hide)
    )
    (property "Dielectric" "" (id 10) (at 72.136 115.316 0)
      (effects (font (size 1.27 1.27)) (justify left bottom) hide)
    )
    (pin "1")
    (pin "2")
  )

  (symbol (lib_id "sa800u-baseboard-hw:GND") (at 102.616 100.076 0) (unit 1)
    (in_bom yes) (on_board yes) (fields_autoplaced)
    (property "Reference" "#PWR0183" (id 0) (at 102.616 106.426 0)
      (effects (font (size 1.27 1.27)) hide)
    )
    (property "Value" "GND" (id 1) (at 102.616 105.156 0))
    (property "Footprint" "" (id 2) (at 102.616 100.076 0)
      (effects (font (size 1.27 1.27)) hide)
    )
    (property "Datasheet" "" (id 3) (at 102.616 100.076 0)
      (effects (font (size 1.27 1.27)) hide)
    )
    (property "Author" "Antmicro" (id 4) (at 111.506 107.696 0)
      (effects (font (size 1.27 1.27) (thickness 0.15)) (justify left bottom) hide)
    )
    (property "License" "Apache-2.0" (id 5) (at 111.506 110.236 0)
      (effects (font (size 1.27 1.27) (thickness 0.15)) (justify left bottom) hide)
    )
    (pin "1")
  )

  (symbol (lib_id "sa800u-baseboard-hw:C_1u_0402") (at 90.551 94.996 270) (unit 1)
    (in_bom yes) (on_board yes) (fields_autoplaced)
    (property "Reference" "C111" (id 0) (at 93.726 96.2723 90)
      (effects (font (size 1.524 1.524)) (justify left))
    )
    (property "Value" "C_1u_0402" (id 1) (at 86.741 94.996 0)
      (effects (font (size 1.524 1.524)) hide)
    )
    (property "Footprint" "sa800u-baseboard-hw-footprints:C_0402_1005Metric" (id 2) (at 95.631 100.076 0)
      (effects (font (size 1.524 1.524)) (justify left) hide)
    )
    (property "Datasheet" " " (id 3) (at 90.551 94.996 0)
      (effects (font (size 1.27 1.27)) hide)
    )
    (property "Manufacturer" "TDK" (id 4) (at 100.711 100.076 0)
      (effects (font (size 1.524 1.524)) (justify left) hide)
    )
    (property "MPN" "C1005X6S1A105K050BC" (id 5) (at 98.171 100.076 0)
      (effects (font (size 1.524 1.524)) (justify left) hide)
    )
    (property "Val" "1u" (id 6) (at 93.726 99.4472 90)
      (effects (font (size 1.27 1.27)) (justify left))
    )
    (property "License" "Apache-2.0" (id 7) (at 67.691 115.316 0)
      (effects (font (size 1.27 1.27) (thickness 0.15)) (justify left bottom) hide)
    )
    (property "Author" "Antmicro" (id 8) (at 65.151 115.316 0)
      (effects (font (size 1.27 1.27) (thickness 0.15)) (justify left bottom) hide)
    )
    (property "Voltage" "" (id 9) (at 62.611 115.316 0)
      (effects (font (size 1.27 1.27)) (justify left bottom) hide)
    )
    (property "Dielectric" "" (id 10) (at 60.071 115.316 0)
      (effects (font (size 1.27 1.27)) (justify left bottom) hide)
    )
    (pin "1")
    (pin "2")
  )

  (symbol (lib_id "sa800u-baseboard-hw:GND") (at 90.551 100.076 0) (unit 1)
    (in_bom yes) (on_board yes) (fields_autoplaced)
    (property "Reference" "#PWR0182" (id 0) (at 90.551 106.426 0)
      (effects (font (size 1.27 1.27)) hide)
    )
    (property "Value" "GND" (id 1) (at 90.551 105.156 0))
    (property "Footprint" "" (id 2) (at 90.551 100.076 0)
      (effects (font (size 1.27 1.27)) hide)
    )
    (property "Datasheet" "" (id 3) (at 90.551 100.076 0)
      (effects (font (size 1.27 1.27)) hide)
    )
    (property "Author" "Antmicro" (id 4) (at 99.441 107.696 0)
      (effects (font (size 1.27 1.27) (thickness 0.15)) (justify left bottom) hide)
    )
    (property "License" "Apache-2.0" (id 5) (at 99.441 110.236 0)
      (effects (font (size 1.27 1.27) (thickness 0.15)) (justify left bottom) hide)
    )
    (pin "1")
  )

  (symbol (lib_id "sa800u-baseboard-hw:C_1u_0402") (at 126.111 94.996 270) (unit 1)
    (in_bom yes) (on_board yes) (fields_autoplaced)
    (property "Reference" "C114" (id 0) (at 129.159 96.2723 90)
      (effects (font (size 1.524 1.524)) (justify left))
    )
    (property "Value" "C_1u_0402" (id 1) (at 122.301 94.996 0)
      (effects (font (size 1.524 1.524)) hide)
    )
    (property "Footprint" "sa800u-baseboard-hw-footprints:C_0402_1005Metric" (id 2) (at 131.191 100.076 0)
      (effects (font (size 1.524 1.524)) (justify left) hide)
    )
    (property "Datasheet" " " (id 3) (at 126.111 94.996 0)
      (effects (font (size 1.27 1.27)) hide)
    )
    (property "Manufacturer" "TDK" (id 4) (at 136.271 100.076 0)
      (effects (font (size 1.524 1.524)) (justify left) hide)
    )
    (property "MPN" "C1005X6S1A105K050BC" (id 5) (at 133.731 100.076 0)
      (effects (font (size 1.524 1.524)) (justify left) hide)
    )
    (property "Val" "1u" (id 6) (at 129.159 99.4472 90)
      (effects (font (size 1.27 1.27)) (justify left))
    )
    (property "License" "Apache-2.0" (id 7) (at 103.251 115.316 0)
      (effects (font (size 1.27 1.27) (thickness 0.15)) (justify left bottom) hide)
    )
    (property "Author" "Antmicro" (id 8) (at 100.711 115.316 0)
      (effects (font (size 1.27 1.27) (thickness 0.15)) (justify left bottom) hide)
    )
    (property "Voltage" "" (id 9) (at 98.171 115.316 0)
      (effects (font (size 1.27 1.27)) (justify left bottom) hide)
    )
    (property "Dielectric" "" (id 10) (at 95.631 115.316 0)
      (effects (font (size 1.27 1.27)) (justify left bottom) hide)
    )
    (pin "1")
    (pin "2")
  )

  (symbol (lib_id "sa800u-baseboard-hw:GND") (at 126.111 100.076 0) (unit 1)
    (in_bom yes) (on_board yes) (fields_autoplaced)
    (property "Reference" "#PWR0185" (id 0) (at 126.111 106.426 0)
      (effects (font (size 1.27 1.27)) hide)
    )
    (property "Value" "GND" (id 1) (at 126.111 105.156 0))
    (property "Footprint" "" (id 2) (at 126.111 100.076 0)
      (effects (font (size 1.27 1.27)) hide)
    )
    (property "Datasheet" "" (id 3) (at 126.111 100.076 0)
      (effects (font (size 1.27 1.27)) hide)
    )
    (property "Author" "Antmicro" (id 4) (at 135.001 107.696 0)
      (effects (font (size 1.27 1.27) (thickness 0.15)) (justify left bottom) hide)
    )
    (property "License" "Apache-2.0" (id 5) (at 135.001 110.236 0)
      (effects (font (size 1.27 1.27) (thickness 0.15)) (justify left bottom) hide)
    )
    (pin "1")
  )
)
